(kicad_pcb
	(version 20260206)
	(generator "pcbnew")
	(generator_version "10.0")
	(general
		(thickness 1.6)
		(legacy_teardrops no)
	)
	(paper "A4")
	(title_block
		(title "01162023_DA0F0TEBIF0_F0T_Expander_BD_F_brd_V02_OCP.brd")
		(comment 1 "Grand Teton / footprints 3807-3812 of 9728")
	)
	(layers
		(0 "F.Cu" signal "TOP")
		(4 "In1.Cu" signal "GND")
		(6 "In2.Cu" signal "VCC")
		(8 "In3.Cu" signal "VCC1")
		(10 "In4.Cu" signal "GND1")
		(12 "In5.Cu" signal "IN1")
		(14 "In6.Cu" signal "GND2")
		(16 "In7.Cu" signal "IN2")
		(18 "In8.Cu" signal "GND3")
		(20 "In9.Cu" signal "IN3")
		(22 "In10.Cu" signal "GND4")
		(24 "In11.Cu" signal "IN4")
		(26 "In12.Cu" signal "GND5")
		(28 "In13.Cu" signal "IN5")
		(30 "In14.Cu" signal "GND6")
		(32 "In15.Cu" signal "IN6")
		(34 "In16.Cu" signal "GND7")
		(2 "B.Cu" signal "BOTTOM")
		(9 "F.Adhes" user "F.Adhesive")
		(11 "B.Adhes" user "B.Adhesive")
		(13 "F.Paste" user "Package Geometry/Pastemask Top")
		(15 "B.Paste" user "Package Geometry/Pastemask Bottom")
		(5 "F.SilkS" user "Ref Des/Silkscreen Top")
		(7 "B.SilkS" user "Ref Des/Silkscreen Bottom")
		(1 "F.Mask" user "Board Geometry/Soldermask Top")
		(3 "B.Mask" user "Board Geometry/Soldermask Bottom")
		(17 "Dwgs.User" user "User.Drawings")
		(19 "Cmts.User" user "User.Comments")
		(21 "Eco1.User" user "User.Eco1")
		(23 "Eco2.User" user "User.Eco2")
		(25 "Edge.Cuts" user "Board Geometry/Outline")
		(27 "Margin" user)
		(31 "F.CrtYd" user "Package Geometry/Place Bound Top")
		(29 "B.CrtYd" user "Package Geometry/Place Bound Bottom")
		(35 "F.Fab" user "Ref Des/Assembly Top")
		(33 "B.Fab" user "Ref Des/Assembly Bottom")
	)
	(footprint ""
		(layer "F.Cu")
		(at 285.326074 -39.73576 -90)
		(property "Reference" "R5575"
			(at 0 0 270)
			(layer "F.SilkS")
			(hide yes)
			(effects
				(font
					(size 1.27 1.27)
				)
			)
		)
		(property "Value" ""
			(at 0 0 270)
			(layer "F.Fab")
			(effects
				(font
					(size 1.27 1.27)
				)
			)
		)
		(duplicate_pad_numbers_are_jumpers no)
		(fp_line
			(start -0.7874 0.4064)
			(end -0.7874 -0.4064)
			(stroke
				(width 0.1524)
				(type default)
			)
			(layer "F.SilkS")
		)
		(fp_line
			(start 0.7874 0.4064)
			(end -0.7874 0.4064)
			(stroke
				(width 0.1524)
				(type default)
			)
			(layer "F.SilkS")
		)
		(fp_line
			(start -0.7874 -0.4064)
			(end 0.7874 -0.4064)
			(stroke
				(width 0.1524)
				(type default)
			)
			(layer "F.SilkS")
		)
		(fp_line
			(start 0.7874 -0.4064)
			(end 0.7874 0.4064)
			(stroke
				(width 0.1524)
				(type default)
			)
			(layer "F.SilkS")
		)
		(fp_line
			(start -0.67945 0.3048)
			(end -0.67945 -0.305054)
			(stroke
				(width 0.1)
				(type default)
			)
			(layer "F.Fab")
		)
		(fp_line
			(start -0.12065 0.3048)
			(end -0.67945 0.3048)
			(stroke
				(width 0.1)
				(type default)
			)
			(layer "F.Fab")
		)
		(fp_line
			(start 0.120396 0.3048)
			(end 0.120396 0.2794)
			(stroke
				(width 0.1)
				(type default)
			)
			(layer "F.Fab")
		)
		(fp_line
			(start 0.67945 0.3048)
			(end 0.120396 0.3048)
			(stroke
				(width 0.1)
				(type default)
			)
			(layer "F.Fab")
		)
		(fp_line
			(start -0.12065 0.2794)
			(end -0.12065 0.3048)
			(stroke
				(width 0.1)
				(type default)
			)
			(layer "F.Fab")
		)
		(fp_line
			(start 0.120396 0.2794)
			(end -0.12065 0.2794)
			(stroke
				(width 0.1)
				(type default)
			)
			(layer "F.Fab")
		)
		(fp_line
			(start -0.12065 -0.2794)
			(end 0.12065 -0.2794)
			(stroke
				(width 0.1)
				(type default)
			)
			(layer "F.Fab")
		)
		(fp_line
			(start 0.12065 -0.2794)
			(end 0.12065 -0.3048)
			(stroke
				(width 0.1)
				(type default)
			)
			(layer "F.Fab")
		)
		(fp_line
			(start 0.12065 -0.3048)
			(end 0.67945 -0.3048)
			(stroke
				(width 0.1)
				(type default)
			)
			(layer "F.Fab")
		)
		(fp_line
			(start 0.67945 -0.3048)
			(end 0.67945 0.3048)
			(stroke
				(width 0.1)
				(type default)
			)
			(layer "F.Fab")
		)
		(fp_line
			(start -0.67945 -0.305054)
			(end -0.12065 -0.305054)
			(stroke
				(width 0.1)
				(type default)
			)
			(layer "F.Fab")
		)
		(fp_line
			(start -0.12065 -0.305054)
			(end -0.12065 -0.2794)
			(stroke
				(width 0.1)
				(type default)
			)
			(layer "F.Fab")
		)
		(pad "1" smd circle
			(at -0.40005 0 270)
			(size 0 0)
			(layers "F.Cu" "F.Mask" "F.Paste")
			(net "P3V3_AUX")
		)
		(pad "2" smd circle
			(at 0.40005 0 270)
			(size 0 0)
			(layers "F.Cu" "F.Mask" "F.Paste")
			(net "SSD10_AUX_P3V3_EN")
		)
	)
	(footprint ""
		(layer "F.Cu")
		(at 197.457822 -27.006296 -90)
		(property "Reference" "PR7113"
			(at 0 0 270)
			(layer "F.SilkS")
			(hide yes)
			(effects
				(font
					(size 1.27 1.27)
				)
			)
		)
		(property "Value" ""
			(at 0 0 270)
			(layer "F.Fab")
			(effects
				(font
					(size 1.27 1.27)
				)
			)
		)
		(duplicate_pad_numbers_are_jumpers no)
		(fp_line
			(start -0.7874 0.4064)
			(end -0.7874 -0.4064)
			(stroke
				(width 0.1524)
				(type default)
			)
			(layer "F.SilkS")
		)
		(fp_line
			(start 0.7874 0.4064)
			(end -0.7874 0.4064)
			(stroke
				(width 0.1524)
				(type default)
			)
			(layer "F.SilkS")
		)
		(fp_line
			(start -0.7874 -0.4064)
			(end 0.7874 -0.4064)
			(stroke
				(width 0.1524)
				(type default)
			)
			(layer "F.SilkS")
		)
		(fp_line
			(start 0.7874 -0.4064)
			(end 0.7874 0.4064)
			(stroke
				(width 0.1524)
				(type default)
			)
			(layer "F.SilkS")
		)
		(fp_line
			(start -0.67945 0.3048)
			(end -0.67945 -0.305054)
			(stroke
				(width 0.1)
				(type default)
			)
			(layer "F.Fab")
		)
		(fp_line
			(start -0.12065 0.3048)
			(end -0.67945 0.3048)
			(stroke
				(width 0.1)
				(type default)
			)
			(layer "F.Fab")
		)
		(fp_line
			(start 0.120396 0.3048)
			(end 0.120396 0.2794)
			(stroke
				(width 0.1)
				(type default)
			)
			(layer "F.Fab")
		)
		(fp_line
			(start 0.67945 0.3048)
			(end 0.120396 0.3048)
			(stroke
				(width 0.1)
				(type default)
			)
			(layer "F.Fab")
		)
		(fp_line
			(start -0.12065 0.2794)
			(end -0.12065 0.3048)
			(stroke
				(width 0.1)
				(type default)
			)
			(layer "F.Fab")
		)
		(fp_line
			(start 0.120396 0.2794)
			(end -0.12065 0.2794)
			(stroke
				(width 0.1)
				(type default)
			)
			(layer "F.Fab")
		)
		(fp_line
			(start -0.12065 -0.2794)
			(end 0.12065 -0.2794)
			(stroke
				(width 0.1)
				(type default)
			)
			(layer "F.Fab")
		)
		(fp_line
			(start 0.12065 -0.2794)
			(end 0.12065 -0.3048)
			(stroke
				(width 0.1)
				(type default)
			)
			(layer "F.Fab")
		)
		(fp_line
			(start 0.12065 -0.3048)
			(end 0.67945 -0.3048)
			(stroke
				(width 0.1)
				(type default)
			)
			(layer "F.Fab")
		)
		(fp_line
			(start 0.67945 -0.3048)
			(end 0.67945 0.3048)
			(stroke
				(width 0.1)
				(type default)
			)
			(layer "F.Fab")
		)
		(fp_line
			(start -0.67945 -0.305054)
			(end -0.12065 -0.305054)
			(stroke
				(width 0.1)
				(type default)
			)
			(layer "F.Fab")
		)
		(fp_line
			(start -0.12065 -0.305054)
			(end -0.12065 -0.2794)
			(stroke
				(width 0.1)
				(type default)
			)
			(layer "F.Fab")
		)
		(pad "1" smd circle
			(at -0.40005 0 270)
			(size 0 0)
			(layers "F.Cu" "F.Mask" "F.Paste")
			(net "P3V3_SSD7_CO_MODE")
		)
		(pad "2" smd circle
			(at 0.40005 0 270)
			(size 0 0)
			(layers "F.Cu" "F.Mask" "F.Paste")
			(net "GND")
		)
	)
	(footprint ""
		(layer "F.Cu")
		(at 137.985754 -25.1587 -90)
		(property "Reference" "R5740"
			(at 0 0 270)
			(layer "F.SilkS")
			(hide yes)
			(effects
				(font
					(size 1.27 1.27)
				)
			)
		)
		(property "Value" ""
			(at 0 0 270)
			(layer "F.Fab")
			(effects
				(font
					(size 1.27 1.27)
				)
			)
		)
		(duplicate_pad_numbers_are_jumpers no)
		(fp_line
			(start -0.7874 0.4064)
			(end -0.7874 -0.4064)
			(stroke
				(width 0.1524)
				(type default)
			)
			(layer "F.SilkS")
		)
		(fp_line
			(start 0.7874 0.4064)
			(end -0.7874 0.4064)
			(stroke
				(width 0.1524)
				(type default)
			)
			(layer "F.SilkS")
		)
		(fp_line
			(start -0.7874 -0.4064)
			(end 0.7874 -0.4064)
			(stroke
				(width 0.1524)
				(type default)
			)
			(layer "F.SilkS")
		)
		(fp_line
			(start 0.7874 -0.4064)
			(end 0.7874 0.4064)
			(stroke
				(width 0.1524)
				(type default)
			)
			(layer "F.SilkS")
		)
		(fp_line
			(start -0.67945 0.3048)
			(end -0.67945 -0.305054)
			(stroke
				(width 0.1)
				(type default)
			)
			(layer "F.Fab")
		)
		(fp_line
			(start -0.12065 0.3048)
			(end -0.67945 0.3048)
			(stroke
				(width 0.1)
				(type default)
			)
			(layer "F.Fab")
		)
		(fp_line
			(start 0.120396 0.3048)
			(end 0.120396 0.2794)
			(stroke
				(width 0.1)
				(type default)
			)
			(layer "F.Fab")
		)
		(fp_line
			(start 0.67945 0.3048)
			(end 0.120396 0.3048)
			(stroke
				(width 0.1)
				(type default)
			)
			(layer "F.Fab")
		)
		(fp_line
			(start -0.12065 0.2794)
			(end -0.12065 0.3048)
			(stroke
				(width 0.1)
				(type default)
			)
			(layer "F.Fab")
		)
		(fp_line
			(start 0.120396 0.2794)
			(end -0.12065 0.2794)
			(stroke
				(width 0.1)
				(type default)
			)
			(layer "F.Fab")
		)
		(fp_line
			(start -0.12065 -0.2794)
			(end 0.12065 -0.2794)
			(stroke
				(width 0.1)
				(type default)
			)
			(layer "F.Fab")
		)
		(fp_line
			(start 0.12065 -0.2794)
			(end 0.12065 -0.3048)
			(stroke
				(width 0.1)
				(type default)
			)
			(layer "F.Fab")
		)
		(fp_line
			(start 0.12065 -0.3048)
			(end 0.67945 -0.3048)
			(stroke
				(width 0.1)
				(type default)
			)
			(layer "F.Fab")
		)
		(fp_line
			(start 0.67945 -0.3048)
			(end 0.67945 0.3048)
			(stroke
				(width 0.1)
				(type default)
			)
			(layer "F.Fab")
		)
		(fp_line
			(start -0.67945 -0.305054)
			(end -0.12065 -0.305054)
			(stroke
				(width 0.1)
				(type default)
			)
			(layer "F.Fab")
		)
		(fp_line
			(start -0.12065 -0.305054)
			(end -0.12065 -0.2794)
			(stroke
				(width 0.1)
				(type default)
			)
			(layer "F.Fab")
		)
		(pad "1" smd circle
			(at -0.40005 0 270)
			(size 0 0)
			(layers "F.Cu" "F.Mask" "F.Paste")
			(net "SSD4_LED_ISO_N")
		)
		(pad "2" smd circle
			(at 0.40005 0 270)
			(size 0 0)
			(layers "F.Cu" "F.Mask" "F.Paste")
			(net "SSD4_LED_ISO_R_N")
		)
	)
	(footprint ""
		(layer "F.Cu")
		(at 439.673746 -298.885102 -90)
		(property "Reference" "R4019"
			(at 0 0 270)
			(layer "F.SilkS")
			(hide yes)
			(effects
				(font
					(size 1.27 1.27)
				)
			)
		)
		(property "Value" ""
			(at 0 0 270)
			(layer "F.Fab")
			(effects
				(font
					(size 1.27 1.27)
				)
			)
		)
		(duplicate_pad_numbers_are_jumpers no)
		(fp_line
			(start -0.7874 0.4064)
			(end -0.7874 -0.4064)
			(stroke
				(width 0.1524)
				(type default)
			)
			(layer "F.SilkS")
		)
		(fp_line
			(start 0.7874 0.4064)
			(end -0.7874 0.4064)
			(stroke
				(width 0.1524)
				(type default)
			)
			(layer "F.SilkS")
		)
		(fp_line
			(start -0.7874 -0.4064)
			(end 0.7874 -0.4064)
			(stroke
				(width 0.1524)
				(type default)
			)
			(layer "F.SilkS")
		)
		(fp_line
			(start 0.7874 -0.4064)
			(end 0.7874 0.4064)
			(stroke
				(width 0.1524)
				(type default)
			)
			(layer "F.SilkS")
		)
		(fp_line
			(start -0.67945 0.3048)
			(end -0.67945 -0.305054)
			(stroke
				(width 0.1)
				(type default)
			)
			(layer "F.Fab")
		)
		(fp_line
			(start -0.12065 0.3048)
			(end -0.67945 0.3048)
			(stroke
				(width 0.1)
				(type default)
			)
			(layer "F.Fab")
		)
		(fp_line
			(start 0.120396 0.3048)
			(end 0.120396 0.2794)
			(stroke
				(width 0.1)
				(type default)
			)
			(layer "F.Fab")
		)
		(fp_line
			(start 0.67945 0.3048)
			(end 0.120396 0.3048)
			(stroke
				(width 0.1)
				(type default)
			)
			(layer "F.Fab")
		)
		(fp_line
			(start -0.12065 0.2794)
			(end -0.12065 0.3048)
			(stroke
				(width 0.1)
				(type default)
			)
			(layer "F.Fab")
		)
		(fp_line
			(start 0.120396 0.2794)
			(end -0.12065 0.2794)
			(stroke
				(width 0.1)
				(type default)
			)
			(layer "F.Fab")
		)
		(fp_line
			(start -0.12065 -0.2794)
			(end 0.12065 -0.2794)
			(stroke
				(width 0.1)
				(type default)
			)
			(layer "F.Fab")
		)
		(fp_line
			(start 0.12065 -0.2794)
			(end 0.12065 -0.3048)
			(stroke
				(width 0.1)
				(type default)
			)
			(layer "F.Fab")
		)
		(fp_line
			(start 0.12065 -0.3048)
			(end 0.67945 -0.3048)
			(stroke
				(width 0.1)
				(type default)
			)
			(layer "F.Fab")
		)
		(fp_line
			(start 0.67945 -0.3048)
			(end 0.67945 0.3048)
			(stroke
				(width 0.1)
				(type default)
			)
			(layer "F.Fab")
		)
		(fp_line
			(start -0.67945 -0.305054)
			(end -0.12065 -0.305054)
			(stroke
				(width 0.1)
				(type default)
			)
			(layer "F.Fab")
		)
		(fp_line
			(start -0.12065 -0.305054)
			(end -0.12065 -0.2794)
			(stroke
				(width 0.1)
				(type default)
			)
			(layer "F.Fab")
		)
		(pad "1" smd circle
			(at -0.40005 0 270)
			(size 0 0)
			(layers "F.Cu" "F.Mask" "F.Paste")
			(net "P1V8_PEX")
		)
		(pad "2" smd circle
			(at 0.40005 0 270)
			(size 0 0)
			(layers "F.Cu" "F.Mask" "F.Paste")
			(net "I2C_PEX3_HOST_R_SCL")
		)
	)
	(footprint ""
		(layer "F.Cu")
		(at 366.955578 -83.784694 180)
		(property "Reference" "R1620"
			(at 0 0 180)
			(layer "F.SilkS")
			(hide yes)
			(effects
				(font
					(size 1.27 1.27)
				)
			)
		)
		(property "Value" ""
			(at 0 0 180)
			(layer "F.Fab")
			(effects
				(font
					(size 1.27 1.27)
				)
			)
		)
		(duplicate_pad_numbers_are_jumpers no)
		(fp_line
			(start 0.7874 0.4064)
			(end -0.7874 0.4064)
			(stroke
				(width 0.1524)
				(type default)
			)
			(layer "F.SilkS")
		)
		(fp_line
			(start 0.7874 -0.4064)
			(end 0.7874 0.4064)
			(stroke
				(width 0.1524)
				(type default)
			)
			(layer "F.SilkS")
		)
		(fp_line
			(start -0.7874 0.4064)
			(end -0.7874 -0.4064)
			(stroke
				(width 0.1524)
				(type default)
			)
			(layer "F.SilkS")
		)
		(fp_line
			(start -0.7874 -0.4064)
			(end 0.7874 -0.4064)
			(stroke
				(width 0.1524)
				(type default)
			)
			(layer "F.SilkS")
		)
		(fp_line
			(start 0.67945 0.3048)
			(end 0.120396 0.3048)
			(stroke
				(width 0.1)
				(type default)
			)
			(layer "F.Fab")
		)
		(fp_line
			(start 0.67945 -0.3048)
			(end 0.67945 0.3048)
			(stroke
				(width 0.1)
				(type default)
			)
			(layer "F.Fab")
		)
		(fp_line
			(start 0.12065 -0.2794)
			(end 0.12065 -0.3048)
			(stroke
				(width 0.1)
				(type default)
			)
			(layer "F.Fab")
		)
		(fp_line
			(start 0.12065 -0.3048)
			(end 0.67945 -0.3048)
			(stroke
				(width 0.1)
				(type default)
			)
			(layer "F.Fab")
		)
		(fp_line
			(start 0.120396 0.3048)
			(end 0.120396 0.2794)
			(stroke
				(width 0.1)
				(type default)
			)
			(layer "F.Fab")
		)
		(fp_line
			(start 0.120396 0.2794)
			(end -0.12065 0.2794)
			(stroke
				(width 0.1)
				(type default)
			)
			(layer "F.Fab")
		)
		(fp_line
			(start -0.12065 0.3048)
			(end -0.67945 0.3048)
			(stroke
				(width 0.1)
				(type default)
			)
			(layer "F.Fab")
		)
		(fp_line
			(start -0.12065 0.2794)
			(end -0.12065 0.3048)
			(stroke
				(width 0.1)
				(type default)
			)
			(layer "F.Fab")
		)
		(fp_line
			(start -0.12065 -0.2794)
			(end 0.12065 -0.2794)
			(stroke
				(width 0.1)
				(type default)
			)
			(layer "F.Fab")
		)
		(fp_line
			(start -0.12065 -0.305054)
			(end -0.12065 -0.2794)
			(stroke
				(width 0.1)
				(type default)
			)
			(layer "F.Fab")
		)
		(fp_line
			(start -0.67945 0.3048)
			(end -0.67945 -0.305054)
			(stroke
				(width 0.1)
				(type default)
			)
			(layer "F.Fab")
		)
		(fp_line
			(start -0.67945 -0.305054)
			(end -0.12065 -0.305054)
			(stroke
				(width 0.1)
				(type default)
			)
			(layer "F.Fab")
		)
		(pad "1" smd circle
			(at -0.40005 0 180)
			(size 0 0)
			(layers "F.Cu" "F.Mask" "F.Paste")
			(net "SMB_BIC_I2C9_MUX1_SSD13_R_SDA")
		)
		(pad "2" smd circle
			(at 0.40005 0 180)
			(size 0 0)
			(layers "F.Cu" "F.Mask" "F.Paste")
			(net "SMB_BIC_I2C9_MUX1_SSD13_SDA")
		)
	)
	(footprint ""
		(layer "F.Cu")
		(at 46.947328 -21.37156)
		(property "Reference" "C3881"
			(at 0 0 0)
			(layer "F.SilkS")
			(hide yes)
			(effects
				(font
					(size 1.27 1.27)
				)
			)
		)
		(property "Value" ""
			(at 0 0 0)
			(layer "F.Fab")
			(effects
				(font
					(size 1.27 1.27)
				)
			)
		)
		(duplicate_pad_numbers_are_jumpers no)
		(fp_line
			(start -0.7874 -0.4064)
			(end 0.7874 -0.4064)
			(stroke
				(width 0.1524)
				(type default)
			)
			(layer "F.SilkS")
		)
		(fp_line
			(start -0.7874 0.4064)
			(end -0.7874 -0.4064)
			(stroke
				(width 0.1524)
				(type default)
			)
			(layer "F.SilkS")
		)
		(fp_line
			(start 0.7874 -0.4064)
			(end 0.7874 0.4064)
			(stroke
				(width 0.1524)
				(type default)
			)
			(layer "F.SilkS")
		)
		(fp_line
			(start 0.7874 0.4064)
			(end -0.7874 0.4064)
			(stroke
				(width 0.1524)
				(type default)
			)
			(layer "F.SilkS")
		)
		(fp_line
			(start -0.67945 -0.305054)
			(end -0.12065 -0.305054)
			(stroke
				(width 0.1)
				(type default)
			)
			(layer "F.Fab")
		)
		(fp_line
			(start -0.67945 0.3048)
			(end -0.67945 -0.305054)
			(stroke
				(width 0.1)
				(type default)
			)
			(layer "F.Fab")
		)
		(fp_line
			(start -0.12065 -0.305054)
			(end -0.12065 -0.2794)
			(stroke
				(width 0.1)
				(type default)
			)
			(layer "F.Fab")
		)
		(fp_line
			(start -0.12065 -0.2794)
			(end 0.12065 -0.2794)
			(stroke
				(width 0.1)
				(type default)
			)
			(layer "F.Fab")
		)
		(fp_line
			(start -0.12065 0.2794)
			(end -0.12065 0.3048)
			(stroke
				(width 0.1)
				(type default)
			)
			(layer "F.Fab")
		)
		(fp_line
			(start -0.12065 0.3048)
			(end -0.67945 0.3048)
			(stroke
				(width 0.1)
				(type default)
			)
			(layer "F.Fab")
		)
		(fp_line
			(start 0.120396 0.2794)
			(end -0.12065 0.2794)
			(stroke
				(width 0.1)
				(type default)
			)
			(layer "F.Fab")
		)
		(fp_line
			(start 0.120396 0.3048)
			(end 0.120396 0.2794)
			(stroke
				(width 0.1)
				(type default)
			)
			(layer "F.Fab")
		)
		(fp_line
			(start 0.12065 -0.3048)
			(end 0.67945 -0.3048)
			(stroke
				(width 0.1)
				(type default)
			)
			(layer "F.Fab")
		)
		(fp_line
			(start 0.12065 -0.2794)
			(end 0.12065 -0.3048)
			(stroke
				(width 0.1)
				(type default)
			)
			(layer "F.Fab")
		)
		(fp_line
			(start 0.67945 -0.3048)
			(end 0.67945 0.3048)
			(stroke
				(width 0.1)
				(type default)
			)
			(layer "F.Fab")
		)
		(fp_line
			(start 0.67945 0.3048)
			(end 0.120396 0.3048)
			(stroke
				(width 0.1)
				(type default)
			)
			(layer "F.Fab")
		)
		(pad "1" smd circle
			(at -0.40005 0)
			(size 0 0)
			(layers "F.Cu" "F.Mask" "F.Paste")
			(net "P12V_SSD1")
		)
		(pad "2" smd circle
			(at 0.40005 0)
			(size 0 0)
			(layers "F.Cu" "F.Mask" "F.Paste")
			(net "GND")
		)
	)
)
